(kicad_pcb
	(version 20260206)
	(generator "pcbnew")
	(generator_version "10.0")
	(general
		(thickness 1.6)
		(legacy_teardrops no)
	)
	(paper "A4")
	(title_block
		(title "Bryce Canyon_IOM_IOC_16318-2_OCP.brd")
		(comment 1 "Bryce Canyon / footprints 848-854 of 1605")
	)
	(layers
		(0 "F.Cu" signal "TOP")
		(4 "In1.Cu" signal "L2GND")
		(6 "In2.Cu" signal "L3")
		(8 "In3.Cu" signal "L4VCC")
		(10 "In4.Cu" signal "L5VCC")
		(12 "In5.Cu" signal "L6")
		(14 "In6.Cu" signal "L7GND")
		(2 "B.Cu" signal "BOTTOM")
		(9 "F.Adhes" user "F.Adhesive")
		(11 "B.Adhes" user "B.Adhesive")
		(13 "F.Paste" user "Package Geometry/Pastemask Top")
		(15 "B.Paste" user "Package Geometry/Pastemask Bottom")
		(5 "F.SilkS" user "Ref Des/Silkscreen Top")
		(7 "B.SilkS" user "Ref Des/Silkscreen Bottom")
		(1 "F.Mask" user "Board Geometry/Soldermask Top")
		(3 "B.Mask" user "Board Geometry/Soldermask Bottom")
		(17 "Dwgs.User" user "User.Drawings")
		(19 "Cmts.User" user "User.Comments")
		(21 "Eco1.User" user "User.Eco1")
		(23 "Eco2.User" user "User.Eco2")
		(25 "Edge.Cuts" user "Board Geometry/Outline")
		(27 "Margin" user)
		(31 "F.CrtYd" user "Package Geometry/Place Bound Top")
		(29 "B.CrtYd" user "Package Geometry/Place Bound Bottom")
		(35 "F.Fab" user "Ref Des/Assembly Top")
		(33 "B.Fab" user "Ref Des/Assembly Bottom")
	)
	(footprint ""
		(layer "F.Cu")
		(at 69.867018 -141.59992 -90)
		(property "Reference" "R601"
			(at 0 0 270)
			(layer "F.SilkS")
			(hide yes)
			(effects
				(font
					(size 1.27 1.27)
				)
			)
		)
		(property "Value" "4K7R2F-GP"
			(at 0.064008 -3.993896 270)
			(unlocked yes)
			(layer "F.Fab")
			(hide yes)
			(effects
				(font
					(size 1.016 1.016)
					(thickness 0.1524)
				)
			)
		)
		(property "Device Type" "R402H16"
			(at 0.064008 -5.517896 270)
			(unlocked yes)
			(layer "F.Fab")
			(hide yes)
			(effects
				(font
					(size 1.016 1.016)
					(thickness 0.1524)
				)
			)
		)
		(duplicate_pad_numbers_are_jumpers no)
		(fp_line
			(start -0.508 -0.9398)
			(end -0.508 0.9398)
			(stroke
				(width 0.1524)
				(type default)
			)
			(layer "F.SilkS")
		)
		(fp_line
			(start 0.508 -0.9398)
			(end -0.508 -0.9398)
			(stroke
				(width 0.1524)
				(type default)
			)
			(layer "F.SilkS")
		)
		(fp_rect
			(start -0.508 0.9398)
			(end 0.508 -0.9398)
			(stroke
				(width 0)
				(type default)
			)
			(fill no)
			(layer "F.CrtYd")
		)
		(fp_rect
			(start -0.508 0.9398)
			(end 0.508 -0.9398)
			(stroke
				(width 0)
				(type default)
			)
			(fill no)
			(layer "F.Fab")
		)
		(pad "1" smd custom
			(at 0 -0.4445 270)
			(size 0.1397 0.1397)
			(layers "F.Cu" "F.Mask" "F.Paste")
			(net "P3V3_STBY")
			(options
				(clearance outline)
				(anchor circle)
			)
			(primitives
				(gr_poly
					(pts
						(arc
							(start -0.1778 -0.2794)
							(mid -0.249642 -0.249642)
							(end -0.2794 -0.1778)
						)
						(arc
							(start -0.2794 0.1778)
							(mid -0.249642 0.249642)
							(end -0.1778 0.2794)
						)
						(arc
							(start 0.1778 0.2794)
							(mid 0.249642 0.249642)
							(end 0.2794 0.1778)
						)
						(arc
							(start 0.2794 -0.1778)
							(mid 0.249642 -0.249642)
							(end 0.1778 -0.2794)
						)
					)
					(width 0)
					(fill yes)
				)
			)
		)
		(pad "2" smd custom
			(at 0 0.4445 270)
			(size 0.1397 0.1397)
			(layers "F.Cu" "F.Mask" "F.Paste")
			(net "I2C_COMP_ALERT_N")
			(options
				(clearance outline)
				(anchor circle)
			)
			(primitives
				(gr_poly
					(pts
						(arc
							(start -0.1778 -0.2794)
							(mid -0.249642 -0.249642)
							(end -0.2794 -0.1778)
						)
						(arc
							(start -0.2794 0.1778)
							(mid -0.249642 0.249642)
							(end -0.1778 0.2794)
						)
						(arc
							(start 0.1778 0.2794)
							(mid 0.249642 0.249642)
							(end 0.2794 0.1778)
						)
						(arc
							(start 0.2794 -0.1778)
							(mid 0.249642 -0.249642)
							(end 0.1778 -0.2794)
						)
					)
					(width 0)
					(fill yes)
				)
			)
		)
	)
	(footprint ""
		(layer "F.Cu")
		(at 158.379668 -143.624808 180)
		(property "Reference" "R518"
			(at 0 0 180)
			(layer "F.SilkS")
			(hide yes)
			(effects
				(font
					(size 1.27 1.27)
				)
			)
		)
		(property "Value" "10KR2F-2-GP"
			(at 0.064008 -3.993896 180)
			(unlocked yes)
			(layer "F.Fab")
			(hide yes)
			(effects
				(font
					(size 1.016 1.016)
					(thickness 0.1524)
				)
			)
		)
		(property "Device Type" "R402H16"
			(at 0.064008 -5.517896 180)
			(unlocked yes)
			(layer "F.Fab")
			(hide yes)
			(effects
				(font
					(size 1.016 1.016)
					(thickness 0.1524)
				)
			)
		)
		(duplicate_pad_numbers_are_jumpers no)
		(fp_line
			(start 0.508 -0.9398)
			(end -0.508 -0.9398)
			(stroke
				(width 0.1524)
				(type default)
			)
			(layer "F.SilkS")
		)
		(fp_line
			(start -0.508 -0.9398)
			(end -0.508 0.9398)
			(stroke
				(width 0.1524)
				(type default)
			)
			(layer "F.SilkS")
		)
		(fp_rect
			(start -0.508 0.9398)
			(end 0.508 -0.9398)
			(stroke
				(width 0)
				(type default)
			)
			(fill no)
			(layer "F.CrtYd")
		)
		(fp_rect
			(start -0.508 0.9398)
			(end 0.508 -0.9398)
			(stroke
				(width 0)
				(type default)
			)
			(fill no)
			(layer "F.Fab")
		)
		(pad "1" smd custom
			(at 0 -0.4445 180)
			(size 0.1397 0.1397)
			(layers "F.Cu" "F.Mask" "F.Paste")
			(net "P1V8_STBY_VRG5")
			(options
				(clearance outline)
				(anchor circle)
			)
			(primitives
				(gr_poly
					(pts
						(arc
							(start -0.1778 -0.2794)
							(mid -0.249642 -0.249642)
							(end -0.2794 -0.1778)
						)
						(arc
							(start -0.2794 0.1778)
							(mid -0.249642 0.249642)
							(end -0.1778 0.2794)
						)
						(arc
							(start 0.1778 0.2794)
							(mid 0.249642 0.249642)
							(end 0.2794 0.1778)
						)
						(arc
							(start 0.2794 -0.1778)
							(mid 0.249642 -0.249642)
							(end 0.1778 -0.2794)
						)
					)
					(width 0)
					(fill yes)
				)
			)
		)
		(pad "2" smd custom
			(at 0 0.4445 180)
			(size 0.1397 0.1397)
			(layers "F.Cu" "F.Mask" "F.Paste")
			(net "PWRGD_P1V8_STBY")
			(options
				(clearance outline)
				(anchor circle)
			)
			(primitives
				(gr_poly
					(pts
						(arc
							(start -0.1778 -0.2794)
							(mid -0.249642 -0.249642)
							(end -0.2794 -0.1778)
						)
						(arc
							(start -0.2794 0.1778)
							(mid -0.249642 0.249642)
							(end -0.1778 0.2794)
						)
						(arc
							(start 0.1778 0.2794)
							(mid 0.249642 0.249642)
							(end 0.2794 0.1778)
						)
						(arc
							(start 0.2794 -0.1778)
							(mid 0.249642 -0.249642)
							(end 0.1778 -0.2794)
						)
					)
					(width 0)
					(fill yes)
				)
			)
		)
	)
	(footprint ""
		(layer "F.Cu")
		(at 33.5534 -165.0238 180)
		(property "Reference" "R705"
			(at 0 0 180)
			(layer "F.SilkS")
			(hide yes)
			(effects
				(font
					(size 1.27 1.27)
				)
			)
		)
		(property "Value" "4K7R2F-GP"
			(at 0.064008 -3.993896 180)
			(unlocked yes)
			(layer "F.Fab")
			(hide yes)
			(effects
				(font
					(size 1.016 1.016)
					(thickness 0.1524)
				)
			)
		)
		(property "Device Type" "R402H16"
			(at 0.064008 -5.517896 180)
			(unlocked yes)
			(layer "F.Fab")
			(hide yes)
			(effects
				(font
					(size 1.016 1.016)
					(thickness 0.1524)
				)
			)
		)
		(duplicate_pad_numbers_are_jumpers no)
		(fp_line
			(start 0.508 -0.9398)
			(end -0.508 -0.9398)
			(stroke
				(width 0.1524)
				(type default)
			)
			(layer "F.SilkS")
		)
		(fp_line
			(start -0.508 -0.9398)
			(end -0.508 0.9398)
			(stroke
				(width 0.1524)
				(type default)
			)
			(layer "F.SilkS")
		)
		(fp_rect
			(start -0.508 0.9398)
			(end 0.508 -0.9398)
			(stroke
				(width 0)
				(type default)
			)
			(fill no)
			(layer "F.CrtYd")
		)
		(fp_rect
			(start -0.508 0.9398)
			(end 0.508 -0.9398)
			(stroke
				(width 0)
				(type default)
			)
			(fill no)
			(layer "F.Fab")
		)
		(pad "1" smd custom
			(at 0 -0.4445 180)
			(size 0.1397 0.1397)
			(layers "F.Cu" "F.Mask" "F.Paste")
			(net "IOM_TYPE2")
			(options
				(clearance outline)
				(anchor circle)
			)
			(primitives
				(gr_poly
					(pts
						(arc
							(start -0.1778 -0.2794)
							(mid -0.249642 -0.249642)
							(end -0.2794 -0.1778)
						)
						(arc
							(start -0.2794 0.1778)
							(mid -0.249642 0.249642)
							(end -0.1778 0.2794)
						)
						(arc
							(start 0.1778 0.2794)
							(mid 0.249642 0.249642)
							(end 0.2794 0.1778)
						)
						(arc
							(start 0.2794 -0.1778)
							(mid 0.249642 -0.249642)
							(end 0.1778 -0.2794)
						)
					)
					(width 0)
					(fill yes)
				)
			)
		)
		(pad "2" smd custom
			(at 0 0.4445 180)
			(size 0.1397 0.1397)
			(layers "F.Cu" "F.Mask" "F.Paste")
			(net "P3V3_STBY")
			(options
				(clearance outline)
				(anchor circle)
			)
			(primitives
				(gr_poly
					(pts
						(arc
							(start -0.1778 -0.2794)
							(mid -0.249642 -0.249642)
							(end -0.2794 -0.1778)
						)
						(arc
							(start -0.2794 0.1778)
							(mid -0.249642 0.249642)
							(end -0.1778 0.2794)
						)
						(arc
							(start 0.1778 0.2794)
							(mid 0.249642 0.249642)
							(end 0.2794 0.1778)
						)
						(arc
							(start 0.2794 -0.1778)
							(mid 0.249642 -0.249642)
							(end 0.1778 -0.2794)
						)
					)
					(width 0)
					(fill yes)
				)
			)
		)
	)
	(footprint ""
		(layer "F.Cu")
		(at 47.498 -131.7498 180)
		(property "Reference" "R177"
			(at 0 0 180)
			(layer "F.SilkS")
			(hide yes)
			(effects
				(font
					(size 1.27 1.27)
				)
			)
		)
		(property "Value" "0R2J-2-GP"
			(at 0.064008 -3.993896 180)
			(unlocked yes)
			(layer "F.Fab")
			(hide yes)
			(effects
				(font
					(size 1.016 1.016)
					(thickness 0.1524)
				)
			)
		)
		(property "Device Type" "R402H16"
			(at 0.064008 -5.517896 180)
			(unlocked yes)
			(layer "F.Fab")
			(hide yes)
			(effects
				(font
					(size 1.016 1.016)
					(thickness 0.1524)
				)
			)
		)
		(duplicate_pad_numbers_are_jumpers no)
		(fp_line
			(start 0.508 -0.9398)
			(end -0.508 -0.9398)
			(stroke
				(width 0.1524)
				(type default)
			)
			(layer "F.SilkS")
		)
		(fp_line
			(start -0.508 -0.9398)
			(end -0.508 0.9398)
			(stroke
				(width 0.1524)
				(type default)
			)
			(layer "F.SilkS")
		)
		(fp_rect
			(start -0.508 0.9398)
			(end 0.508 -0.9398)
			(stroke
				(width 0)
				(type default)
			)
			(fill no)
			(layer "F.CrtYd")
		)
		(fp_rect
			(start -0.508 0.9398)
			(end 0.508 -0.9398)
			(stroke
				(width 0)
				(type default)
			)
			(fill no)
			(layer "F.Fab")
		)
		(pad "1" smd custom
			(at 0 -0.4445 180)
			(size 0.1397 0.1397)
			(layers "F.Cu" "F.Mask" "F.Paste")
			(net "I2C_TPM_SCL")
			(options
				(clearance outline)
				(anchor circle)
			)
			(primitives
				(gr_poly
					(pts
						(arc
							(start -0.1778 -0.2794)
							(mid -0.249642 -0.249642)
							(end -0.2794 -0.1778)
						)
						(arc
							(start -0.2794 0.1778)
							(mid -0.249642 0.249642)
							(end -0.1778 0.2794)
						)
						(arc
							(start 0.1778 0.2794)
							(mid 0.249642 0.249642)
							(end 0.2794 0.1778)
						)
						(arc
							(start 0.2794 -0.1778)
							(mid 0.249642 -0.249642)
							(end 0.1778 -0.2794)
						)
					)
					(width 0)
					(fill yes)
				)
			)
		)
		(pad "2" smd custom
			(at 0 0.4445 180)
			(size 0.1397 0.1397)
			(layers "F.Cu" "F.Mask" "F.Paste")
			(net "BMC_SMB14_CLK")
			(options
				(clearance outline)
				(anchor circle)
			)
			(primitives
				(gr_poly
					(pts
						(arc
							(start -0.1778 -0.2794)
							(mid -0.249642 -0.249642)
							(end -0.2794 -0.1778)
						)
						(arc
							(start -0.2794 0.1778)
							(mid -0.249642 0.249642)
							(end -0.1778 0.2794)
						)
						(arc
							(start 0.1778 0.2794)
							(mid 0.249642 0.249642)
							(end 0.2794 0.1778)
						)
						(arc
							(start 0.2794 -0.1778)
							(mid 0.249642 -0.249642)
							(end 0.1778 -0.2794)
						)
					)
					(width 0)
					(fill yes)
				)
			)
		)
	)
	(footprint ""
		(layer "F.Cu")
		(at 197.06209 -105.784142)
		(property "Reference" "C268"
			(at 0 0 0)
			(layer "F.SilkS")
			(hide yes)
			(effects
				(font
					(size 1.27 1.27)
				)
			)
		)
		(property "Value" "SC22U6D3V6KX-2-GP"
			(at -0.0762 -5.1308 0)
			(unlocked yes)
			(layer "F.Fab")
			(hide yes)
			(effects
				(font
					(size 1.016 1.016)
					(thickness 0.1524)
				)
			)
		)
		(property "Device Type" "C1206H71"
			(at -0.127 -6.6548 0)
			(unlocked yes)
			(layer "F.Fab")
			(hide yes)
			(effects
				(font
					(size 1.016 1.016)
					(thickness 0.1524)
				)
			)
		)
		(duplicate_pad_numbers_are_jumpers no)
		(fp_line
			(start -1.016 -2.2352)
			(end 1.016 -2.2352)
			(stroke
				(width 0.1524)
				(type default)
			)
			(layer "F.SilkS")
		)
		(fp_line
			(start -1.016 -0.8382)
			(end -1.016 -2.2352)
			(stroke
				(width 0.1524)
				(type default)
			)
			(layer "F.SilkS")
		)
		(fp_line
			(start -1.016 2.2352)
			(end -1.016 0.8382)
			(stroke
				(width 0.1524)
				(type default)
			)
			(layer "F.SilkS")
		)
		(fp_line
			(start 1.016 -2.2352)
			(end 1.016 -0.8382)
			(stroke
				(width 0.1524)
				(type default)
			)
			(layer "F.SilkS")
		)
		(fp_line
			(start 1.016 0.8382)
			(end 1.016 2.2352)
			(stroke
				(width 0.1524)
				(type default)
			)
			(layer "F.SilkS")
		)
		(fp_line
			(start 1.016 2.2352)
			(end -1.016 2.2352)
			(stroke
				(width 0.1524)
				(type default)
			)
			(layer "F.SilkS")
		)
		(fp_rect
			(start -1.0922 2.3114)
			(end 1.0922 -2.3114)
			(stroke
				(width 0)
				(type default)
			)
			(fill no)
			(layer "F.CrtYd")
		)
		(fp_poly
			(pts
				(xy 1.0922 -2.3114) (xy 1.0922 2.3114) (xy -1.0922 2.3114) (xy -1.0922 -2.3114)
			)
			(stroke
				(width 0)
				(type default)
			)
			(fill no)
			(layer "F.Fab")
		)
		(pad "1" smd rect
			(at 0 -1.397)
			(size 1.651 1.27)
			(layers "F.Cu" "F.Mask" "F.Paste")
			(net "P0V975")
		)
		(pad "2" smd rect
			(at 0 1.397)
			(size 1.651 1.27)
			(layers "F.Cu" "F.Mask" "F.Paste")
			(net "GND")
		)
	)
	(footprint ""
		(layer "F.Cu")
		(at 179.028852 -140.614908 90)
		(property "Reference" "R476"
			(at 0 0 90)
			(layer "F.SilkS")
			(hide yes)
			(effects
				(font
					(size 1.27 1.27)
				)
			)
		)
		(property "Value" "866KR2F-GP"
			(at 0.064008 -3.993896 90)
			(unlocked yes)
			(layer "F.Fab")
			(hide yes)
			(effects
				(font
					(size 1.016 1.016)
					(thickness 0.1524)
				)
			)
		)
		(property "Device Type" "R402H16"
			(at 0.064008 -5.517896 90)
			(unlocked yes)
			(layer "F.Fab")
			(hide yes)
			(effects
				(font
					(size 1.016 1.016)
					(thickness 0.1524)
				)
			)
		)
		(duplicate_pad_numbers_are_jumpers no)
		(fp_line
			(start 0.508 -0.9398)
			(end -0.508 -0.9398)
			(stroke
				(width 0.1524)
				(type default)
			)
			(layer "F.SilkS")
		)
		(fp_line
			(start -0.508 -0.9398)
			(end -0.508 0.9398)
			(stroke
				(width 0.1524)
				(type default)
			)
			(layer "F.SilkS")
		)
		(fp_rect
			(start -0.508 0.9398)
			(end 0.508 -0.9398)
			(stroke
				(width 0)
				(type default)
			)
			(fill no)
			(layer "F.CrtYd")
		)
		(fp_rect
			(start -0.508 0.9398)
			(end 0.508 -0.9398)
			(stroke
				(width 0)
				(type default)
			)
			(fill no)
			(layer "F.Fab")
		)
		(pad "1" smd custom
			(at 0 -0.4445 90)
			(size 0.1397 0.1397)
			(layers "F.Cu" "F.Mask" "F.Paste")
			(net "P5V_STBY_VREG")
			(options
				(clearance outline)
				(anchor circle)
			)
			(primitives
				(gr_poly
					(pts
						(arc
							(start -0.1778 -0.2794)
							(mid -0.249642 -0.249642)
							(end -0.2794 -0.1778)
						)
						(arc
							(start -0.2794 0.1778)
							(mid -0.249642 0.249642)
							(end -0.1778 0.2794)
						)
						(arc
							(start 0.1778 0.2794)
							(mid 0.249642 0.249642)
							(end 0.2794 0.1778)
						)
						(arc
							(start 0.2794 -0.1778)
							(mid 0.249642 -0.249642)
							(end 0.1778 -0.2794)
						)
					)
					(width 0)
					(fill yes)
				)
			)
		)
		(pad "2" smd custom
			(at 0 0.4445 90)
			(size 0.1397 0.1397)
			(layers "F.Cu" "F.Mask" "F.Paste")
			(net "P5V_RF")
			(options
				(clearance outline)
				(anchor circle)
			)
			(primitives
				(gr_poly
					(pts
						(arc
							(start -0.1778 -0.2794)
							(mid -0.249642 -0.249642)
							(end -0.2794 -0.1778)
						)
						(arc
							(start -0.2794 0.1778)
							(mid -0.249642 0.249642)
							(end -0.1778 0.2794)
						)
						(arc
							(start 0.1778 0.2794)
							(mid 0.249642 0.249642)
							(end 0.2794 0.1778)
						)
						(arc
							(start 0.2794 -0.1778)
							(mid 0.249642 -0.249642)
							(end 0.1778 -0.2794)
						)
					)
					(width 0)
					(fill yes)
				)
			)
		)
	)
	(footprint ""
		(layer "F.Cu")
		(at 63.119 -165.735 90)
		(property "Reference" "Q3"
			(at 0 0 90)
			(layer "F.SilkS")
			(hide yes)
			(effects
				(font
					(size 1.27 1.27)
				)
			)
		)
		(property "Value" "MMBT3904-3-GP"
			(at 0.10287 -10.29843 90)
			(unlocked yes)
			(layer "F.Fab")
			(hide yes)
			(effects
				(font
					(size 1.016 1.016)
					(thickness 0.1524)
				)
			)
		)
		(property "Device Type" "SOT23CBE2D4H44"
			(at 0.10287 -12.20343 90)
			(unlocked yes)
			(layer "F.Fab")
			(hide yes)
			(effects
				(font
					(size 1.016 1.016)
					(thickness 0.1524)
				)
			)
		)
		(duplicate_pad_numbers_are_jumpers no)
		(fp_line
			(start 1.651 -1.778)
			(end -1.651 -1.778)
			(stroke
				(width 0.1524)
				(type default)
			)
			(layer "F.SilkS")
		)
		(fp_line
			(start -1.651 -1.778)
			(end -1.651 1.778)
			(stroke
				(width 0.1524)
				(type default)
			)
			(layer "F.SilkS")
		)
		(fp_line
			(start 1.651 1.778)
			(end 1.651 -1.778)
			(stroke
				(width 0.1524)
				(type default)
			)
			(layer "F.SilkS")
		)
		(fp_line
			(start -1.651 1.778)
			(end 1.651 1.778)
			(stroke
				(width 0.1524)
				(type default)
			)
			(layer "F.SilkS")
		)
		(fp_poly
			(pts
				(xy -1.778 1.8796) (xy -1.778 -1.8796) (xy 1.778 -1.8796) (xy 1.778 1.8796)
			)
			(stroke
				(width 0)
				(type default)
			)
			(fill no)
			(layer "F.CrtYd")
		)
		(fp_poly
			(pts
				(xy -1.778 1.8796) (xy -1.778 -1.8796) (xy 1.778 -1.8796) (xy 1.778 1.8796)
			)
			(stroke
				(width 0)
				(type default)
			)
			(fill no)
			(layer "F.Fab")
		)
		(pad "B" smd custom
			(at -0.98425 0.9525 90)
			(size 0.1905 0.1905)
			(layers "F.Cu" "F.Mask" "F.Paste")
			(net "FM_TPM_PRSNT_RST_N_R")
			(options
				(clearance outline)
				(anchor circle)
			)
			(primitives
				(gr_poly
					(pts
						(arc
							(start -0.1778 0.5715)
							(mid -0.321484 0.511984)
							(end -0.381 0.3683)
						)
						(arc
							(start -0.381 -0.3683)
							(mid -0.321484 -0.511984)
							(end -0.1778 -0.5715)
						)
						(arc
							(start 0.1778 -0.5715)
							(mid 0.321484 -0.511984)
							(end 0.381 -0.3683)
						)
						(arc
							(start 0.381 0.3683)
							(mid 0.321484 0.511984)
							(end 0.1778 0.5715)
						)
					)
					(width 0)
					(fill yes)
				)
			)
		)
		(pad "C" smd custom
			(at 0 -0.9525 90)
			(size 0.1905 0.1905)
			(layers "F.Cu" "F.Mask" "F.Paste")
			(net "FM_TPM_PRSNT_RST")
			(options
				(clearance outline)
				(anchor circle)
			)
			(primitives
				(gr_poly
					(pts
						(arc
							(start -0.1778 0.5715)
							(mid -0.321484 0.511984)
							(end -0.381 0.3683)
						)
						(arc
							(start -0.381 -0.3683)
							(mid -0.321484 -0.511984)
							(end -0.1778 -0.5715)
						)
						(arc
							(start 0.1778 -0.5715)
							(mid 0.321484 -0.511984)
							(end 0.381 -0.3683)
						)
						(arc
							(start 0.381 0.3683)
							(mid 0.321484 0.511984)
							(end 0.1778 0.5715)
						)
					)
					(width 0)
					(fill yes)
				)
			)
		)
		(pad "E" smd custom
			(at 0.98425 0.9525 90)
			(size 0.1905 0.1905)
			(layers "F.Cu" "F.Mask" "F.Paste")
			(net "GND")
			(options
				(clearance outline)
				(anchor circle)
			)
			(primitives
				(gr_poly
					(pts
						(arc
							(start -0.1778 0.5715)
							(mid -0.321484 0.511984)
							(end -0.381 0.3683)
						)
						(arc
							(start -0.381 -0.3683)
							(mid -0.321484 -0.511984)
							(end -0.1778 -0.5715)
						)
						(arc
							(start 0.1778 -0.5715)
							(mid 0.321484 -0.511984)
							(end 0.381 -0.3683)
						)
						(arc
							(start 0.381 0.3683)
							(mid 0.321484 0.511984)
							(end 0.1778 0.5715)
						)
					)
					(width 0)
					(fill yes)
				)
			)
		)
	)
)
